# T6G (Grand Teton) — schematic netlist excerpt (pin names and nets, part order shuffled) for the footprints in the layout excerpt that follows; sources: Cadence DE-HDL packaged netlist, KiCad conversion of 04192023_DAF0TMB3IC0_F0TG_MB_C_brd_V02_OCP.brd

R6807  Q_RES  0 5% CHIP  pkg 0402LF  page 81 : A = RST_RT_CPU0_P1_RESET_R_N ; B = RST_RT_CPU0_P1_RESET_R2_N
C3902  Q_CAP  22UF 4V 20% X6S  pkg C0402  page 72 : A = PVDD11_S3_P1 ; B = GND

(kicad_pcb
	(version 20260206)
	(generator "pcbnew")
	(generator_version "10.0")
	(general
		(thickness 1.6)
		(legacy_teardrops no)
	)
	(paper "A4")
	(title_block
		(title "04192023_DAF0TMB3IC0_F0TG_MB_C_brd_V02_OCP.brd")
		(comment 1 "Grand Teton / footprints 6829-6830 of 8354")
	)
	(layers
		(0 "F.Cu" signal "TOP")
		(4 "In1.Cu" signal "GND")
		(6 "In2.Cu" signal "IN1")
		(8 "In3.Cu" signal "GND1")
		(10 "In4.Cu" signal "IN2")
		(12 "In5.Cu" signal "GND2")
		(14 "In6.Cu" signal "IN3")
		(16 "In7.Cu" signal "GND3")
		(18 "In8.Cu" signal "VCC")
		(20 "In9.Cu" signal "VCC1")
		(22 "In10.Cu" signal "GND4")
		(24 "In11.Cu" signal "IN4")
		(26 "In12.Cu" signal "GND5")
		(28 "In13.Cu" signal "IN5")
		(30 "In14.Cu" signal "GND6")
		(32 "In15.Cu" signal "IN6")
		(34 "In16.Cu" signal "GND7")
		(2 "B.Cu" signal "BOTTOM")
		(9 "F.Adhes" user "F.Adhesive")
		(11 "B.Adhes" user "B.Adhesive")
		(13 "F.Paste" user "Package Geometry/Pastemask Top")
		(15 "B.Paste" user "Package Geometry/Pastemask Bottom")
		(5 "F.SilkS" user "Ref Des/Silkscreen Top")
		(7 "B.SilkS" user "Ref Des/Silkscreen Bottom")
		(1 "F.Mask" user "Board Geometry/Soldermask Top")
		(3 "B.Mask" user "Board Geometry/Soldermask Bottom")
		(17 "Dwgs.User" user "User.Drawings")
		(19 "Cmts.User" user "User.Comments")
		(21 "Eco1.User" user "User.Eco1")
		(23 "Eco2.User" user "User.Eco2")
		(25 "Edge.Cuts" user "Board Geometry/Outline")
		(27 "Margin" user)
		(31 "F.CrtYd" user "Package Geometry/Place Bound Top")
		(29 "B.CrtYd" user "Package Geometry/Place Bound Bottom")
		(35 "F.Fab" user "Ref Des/Assembly Top")
		(33 "B.Fab" user "Ref Des/Assembly Bottom")
	)
	(footprint ""
		(layer "B.Cu")
		(at 108.371386 -264.354564)
		(property "Reference" "C3902"
			(at 0 0 0)
			(layer "B.SilkS")
			(hide yes)
			(effects
				(font
					(size 1.27 1.27)
				)
				(justify mirror)
			)
		)
		(property "Value" ""
			(at 0 0 0)
			(layer "B.Fab")
			(effects
				(font
					(size 1.27 1.27)
				)
				(justify mirror)
			)
		)
		(duplicate_pad_numbers_are_jumpers no)
		(fp_line
			(start -0.7874 -0.4064)
			(end -0.7874 0.4064)
			(stroke
				(width 0.1524)
				(type default)
			)
			(layer "B.SilkS")
		)
		(fp_line
			(start -0.7874 0.4064)
			(end 0.7874 0.4064)
			(stroke
				(width 0.1524)
				(type default)
			)
			(layer "B.SilkS")
		)
		(fp_line
			(start 0.7874 -0.4064)
			(end -0.7874 -0.4064)
			(stroke
				(width 0.1524)
				(type default)
			)
			(layer "B.SilkS")
		)
		(fp_line
			(start 0.7874 0.4064)
			(end 0.7874 -0.4064)
			(stroke
				(width 0.1524)
				(type default)
			)
			(layer "B.SilkS")
		)
		(fp_line
			(start -0.67945 -0.3048)
			(end -0.67945 0.3048)
			(stroke
				(width 0.1)
				(type default)
			)
			(layer "B.Fab")
		)
		(fp_line
			(start -0.67945 0.3048)
			(end -0.120396 0.3048)
			(stroke
				(width 0.1)
				(type default)
			)
			(layer "B.Fab")
		)
		(fp_line
			(start -0.12065 -0.3048)
			(end -0.67945 -0.3048)
			(stroke
				(width 0.1)
				(type default)
			)
			(layer "B.Fab")
		)
		(fp_line
			(start -0.12065 -0.2794)
			(end -0.12065 -0.3048)
			(stroke
				(width 0.1)
				(type default)
			)
			(layer "B.Fab")
		)
		(fp_line
			(start -0.120396 0.2794)
			(end 0.12065 0.2794)
			(stroke
				(width 0.1)
				(type default)
			)
			(layer "B.Fab")
		)
		(fp_line
			(start -0.120396 0.3048)
			(end -0.120396 0.2794)
			(stroke
				(width 0.1)
				(type default)
			)
			(layer "B.Fab")
		)
		(fp_line
			(start 0.12065 -0.305054)
			(end 0.12065 -0.2794)
			(stroke
				(width 0.1)
				(type default)
			)
			(layer "B.Fab")
		)
		(fp_line
			(start 0.12065 -0.2794)
			(end -0.12065 -0.2794)
			(stroke
				(width 0.1)
				(type default)
			)
			(layer "B.Fab")
		)
		(fp_line
			(start 0.12065 0.2794)
			(end 0.12065 0.3048)
			(stroke
				(width 0.1)
				(type default)
			)
			(layer "B.Fab")
		)
		(fp_line
			(start 0.12065 0.3048)
			(end 0.67945 0.3048)
			(stroke
				(width 0.1)
				(type default)
			)
			(layer "B.Fab")
		)
		(fp_line
			(start 0.67945 -0.305054)
			(end 0.12065 -0.305054)
			(stroke
				(width 0.1)
				(type default)
			)
			(layer "B.Fab")
		)
		(fp_line
			(start 0.67945 0.3048)
			(end 0.67945 -0.305054)
			(stroke
				(width 0.1)
				(type default)
			)
			(layer "B.Fab")
		)
		(pad "1" smd circle
			(at 0.40005 0 180)
			(size 0 0)
			(layers "B.Cu" "B.Mask" "B.Paste")
			(net "PVDD11_S3_P1")
		)
		(pad "2" smd circle
			(at -0.40005 0 180)
			(size 0 0)
			(layers "B.Cu" "B.Mask" "B.Paste")
			(net "GND")
		)
	)
	(footprint ""
		(layer "B.Cu")
		(at 205.146148 -129.074164)
		(property "Reference" "R6807"
			(at 0 0 0)
			(layer "B.SilkS")
			(hide yes)
			(effects
				(font
					(size 1.27 1.27)
				)
				(justify mirror)
			)
		)
		(property "Value" ""
			(at 0 0 0)
			(layer "B.Fab")
			(effects
				(font
					(size 1.27 1.27)
				)
				(justify mirror)
			)
		)
		(duplicate_pad_numbers_are_jumpers no)
		(fp_line
			(start -0.7874 -0.4064)
			(end -0.7874 0.4064)
			(stroke
				(width 0.1524)
				(type default)
			)
			(layer "B.SilkS")
		)
		(fp_line
			(start -0.7874 0.4064)
			(end 0.7874 0.4064)
			(stroke
				(width 0.1524)
				(type default)
			)
			(layer "B.SilkS")
		)
		(fp_line
			(start 0.7874 -0.4064)
			(end -0.7874 -0.4064)
			(stroke
				(width 0.1524)
				(type default)
			)
			(layer "B.SilkS")
		)
		(fp_line
			(start 0.7874 0.4064)
			(end 0.7874 -0.4064)
			(stroke
				(width 0.1524)
				(type default)
			)
			(layer "B.SilkS")
		)
		(fp_line
			(start -0.67945 -0.3048)
			(end -0.67945 0.3048)
			(stroke
				(width 0.1)
				(type default)
			)
			(layer "B.Fab")
		)
		(fp_line
			(start -0.67945 0.3048)
			(end -0.120396 0.3048)
			(stroke
				(width 0.1)
				(type default)
			)
			(layer "B.Fab")
		)
		(fp_line
			(start -0.12065 -0.3048)
			(end -0.67945 -0.3048)
			(stroke
				(width 0.1)
				(type default)
			)
			(layer "B.Fab")
		)
		(fp_line
			(start -0.12065 -0.2794)
			(end -0.12065 -0.3048)
			(stroke
				(width 0.1)
				(type default)
			)
			(layer "B.Fab")
		)
		(fp_line
			(start -0.120396 0.2794)
			(end 0.12065 0.2794)
			(stroke
				(width 0.1)
				(type default)
			)
			(layer "B.Fab")
		)
		(fp_line
			(start -0.120396 0.3048)
			(end -0.120396 0.2794)
			(stroke
				(width 0.1)
				(type default)
			)
			(layer "B.Fab")
		)
		(fp_line
			(start 0.12065 -0.305054)
			(end 0.12065 -0.2794)
			(stroke
				(width 0.1)
				(type default)
			)
			(layer "B.Fab")
		)
		(fp_line
			(start 0.12065 -0.2794)
			(end -0.12065 -0.2794)
			(stroke
				(width 0.1)
				(type default)
			)
			(layer "B.Fab")
		)
		(fp_line
			(start 0.12065 0.2794)
			(end 0.12065 0.3048)
			(stroke
				(width 0.1)
				(type default)
			)
			(layer "B.Fab")
		)
		(fp_line
			(start 0.12065 0.3048)
			(end 0.67945 0.3048)
			(stroke
				(width 0.1)
				(type default)
			)
			(layer "B.Fab")
		)
		(fp_line
			(start 0.67945 -0.305054)
			(end 0.12065 -0.305054)
			(stroke
				(width 0.1)
				(type default)
			)
			(layer "B.Fab")
		)
		(fp_line
			(start 0.67945 0.3048)
			(end 0.67945 -0.305054)
			(stroke
				(width 0.1)
				(type default)
			)
			(layer "B.Fab")
		)
		(pad "1" smd circle
			(at 0.40005 0 180)
			(size 0 0)
			(layers "B.Cu" "B.Mask" "B.Paste")
			(net "RST_RT_CPU0_P1_RESET_R_N")
		)
		(pad "2" smd circle
			(at -0.40005 0 180)
			(size 0 0)
			(layers "B.Cu" "B.Mask" "B.Paste")
			(net "RST_RT_CPU0_P1_RESET_R2_N")
		)
	)
)
